(kicad_pcb
	(version 20260206)
	(generator "pcbnew")
	(generator_version "10.0")
	(general
		(thickness 1.6)
		(legacy_teardrops no)
	)
	(paper "A4")
	(title_block
		(title "01162023_DA0F0TEBIF0_F0T_Expander_BD_F_brd_V02_OCP.brd")
		(comment 1 "Grand Teton / footprints 5313-5318 of 9728")
	)
	(layers
		(0 "F.Cu" signal "TOP")
		(4 "In1.Cu" signal "GND")
		(6 "In2.Cu" signal "VCC")
		(8 "In3.Cu" signal "VCC1")
		(10 "In4.Cu" signal "GND1")
		(12 "In5.Cu" signal "IN1")
		(14 "In6.Cu" signal "GND2")
		(16 "In7.Cu" signal "IN2")
		(18 "In8.Cu" signal "GND3")
		(20 "In9.Cu" signal "IN3")
		(22 "In10.Cu" signal "GND4")
		(24 "In11.Cu" signal "IN4")
		(26 "In12.Cu" signal "GND5")
		(28 "In13.Cu" signal "IN5")
		(30 "In14.Cu" signal "GND6")
		(32 "In15.Cu" signal "IN6")
		(34 "In16.Cu" signal "GND7")
		(2 "B.Cu" signal "BOTTOM")
		(9 "F.Adhes" user "F.Adhesive")
		(11 "B.Adhes" user "B.Adhesive")
		(13 "F.Paste" user "Package Geometry/Pastemask Top")
		(15 "B.Paste" user "Package Geometry/Pastemask Bottom")
		(5 "F.SilkS" user "Ref Des/Silkscreen Top")
		(7 "B.SilkS" user "Ref Des/Silkscreen Bottom")
		(1 "F.Mask" user "Board Geometry/Soldermask Top")
		(3 "B.Mask" user "Board Geometry/Soldermask Bottom")
		(17 "Dwgs.User" user "User.Drawings")
		(19 "Cmts.User" user "User.Comments")
		(21 "Eco1.User" user "User.Eco1")
		(23 "Eco2.User" user "User.Eco2")
		(25 "Edge.Cuts" user "Board Geometry/Outline")
		(27 "Margin" user)
		(31 "F.CrtYd" user "Package Geometry/Place Bound Top")
		(29 "B.CrtYd" user "Package Geometry/Place Bound Bottom")
		(35 "F.Fab" user "Ref Des/Assembly Top")
		(33 "B.Fab" user "Ref Des/Assembly Bottom")
	)
	(footprint ""
		(layer "F.Cu")
		(at 130.791204 -284.8991 180)
		(property "Reference" "PU10"
			(at -9.227566 -1.164082 90)
			(unlocked yes)
			(layer "F.SilkS")
			(effects
				(font
					(size 0.7874 0.5842)
					(thickness 0.1524)
				)
			)
		)
		(property "Value" ""
			(at 0 0 180)
			(layer "F.Fab")
			(effects
				(font
					(size 1.27 1.27)
				)
			)
		)
		(duplicate_pad_numbers_are_jumpers no)
		(fp_line
			(start 2.500122 2.999994)
			(end 2.2987 2.999994)
			(stroke
				(width 0.1524)
				(type default)
			)
			(layer "F.SilkS")
		)
		(fp_line
			(start 2.500122 2.339594)
			(end 2.500122 2.999994)
			(stroke
				(width 0.1524)
				(type default)
			)
			(layer "F.SilkS")
		)
		(fp_line
			(start 2.500122 -2.999994)
			(end 2.500122 -2.44348)
			(stroke
				(width 0.1524)
				(type default)
			)
			(layer "F.SilkS")
		)
		(fp_line
			(start 2.31394 -2.999994)
			(end 2.500122 -2.999994)
			(stroke
				(width 0.1524)
				(type default)
			)
			(layer "F.SilkS")
		)
		(fp_line
			(start -2.2987 2.999994)
			(end -2.500122 2.999994)
			(stroke
				(width 0.1524)
				(type default)
			)
			(layer "F.SilkS")
		)
		(fp_line
			(start -2.500122 2.999994)
			(end -2.500122 2.339594)
			(stroke
				(width 0.1524)
				(type default)
			)
			(layer "F.SilkS")
		)
		(fp_line
			(start -2.500122 0.6604)
			(end -2.500122 0.229108)
			(stroke
				(width 0.1524)
				(type default)
			)
			(layer "F.SilkS")
		)
		(fp_line
			(start -2.500122 -2.529078)
			(end -2.500122 -2.999994)
			(stroke
				(width 0.1524)
				(type default)
			)
			(layer "F.SilkS")
		)
		(fp_line
			(start -2.500122 -2.999994)
			(end -2.24409 -2.999994)
			(stroke
				(width 0.1524)
				(type default)
			)
			(layer "F.SilkS")
		)
		(fp_poly
			(pts
				(xy -2.129282 -3.790442) (xy -3.145028 -3.790442) (xy -2.637282 -2.774442)
			)
			(stroke
				(width 0)
				(type default)
			)
			(fill yes)
			(layer "F.SilkS")
		)
		(fp_line
			(start 2.500122 2.999994)
			(end -2.500122 2.999994)
			(stroke
				(width 0.1)
				(type default)
			)
			(layer "F.Fab")
		)
		(fp_line
			(start 2.500122 -2.999994)
			(end 2.500122 2.999994)
			(stroke
				(width 0.1)
				(type default)
			)
			(layer "F.Fab")
		)
		(fp_line
			(start -2.500122 2.999994)
			(end -2.500122 -2.999994)
			(stroke
				(width 0.1)
				(type default)
			)
			(layer "F.Fab")
		)
		(fp_line
			(start -2.500122 -2.999994)
			(end 2.500122 -2.999994)
			(stroke
				(width 0.1)
				(type default)
			)
			(layer "F.Fab")
		)
		(fp_poly
			(pts
				(xy -4.218432 -2.783078) (xy -4.218432 -1.767078) (xy -3.202432 -2.275078)
			)
			(stroke
				(width 0)
				(type default)
			)
			(fill yes)
			(layer "F.Fab")
		)
		(pad "1" smd rect
			(at -2.400046 -2.275078 270)
			(size 0.2286 0.6096)
			(layers "F.Cu" "F.Mask" "F.Paste")
			(net "SW_P0V8_PEX1_VOS2")
		)
		(pad "2" smd rect
			(at -2.400046 -1.82499 270)
			(size 0.2286 0.6096)
			(layers "F.Cu" "F.Mask" "F.Paste")
			(net "GND")
		)
		(pad "3" smd rect
			(at -2.400046 -1.374902 270)
			(size 0.2286 0.6096)
			(layers "F.Cu" "F.Mask" "F.Paste")
			(net "P0V8_PEX1_VCC2")
		)
		(pad "4" smd rect
			(at -2.400046 -0.925068 270)
			(size 0.2286 0.6096)
			(layers "F.Cu" "F.Mask" "F.Paste")
			(net "P0V8_PEX1_PVCC")
		)
		(pad "5" smd rect
			(at -2.400046 -0.47498 270)
			(size 0.2286 0.6096)
			(layers "F.Cu" "F.Mask" "F.Paste")
			(net "GND")
		)
		(pad "6" smd rect
			(at -2.400046 -0.024892 270)
			(size 0.2286 0.6096)
			(layers "F.Cu" "F.Mask" "F.Paste")
			(net "NC_P0V8_PEX1_PH2_NC1")
		)
		(pad "7_9-20_24" smd circle
			(at 0 1.150112 270)
			(size 0 0)
			(layers "F.Cu" "F.Mask" "F.Paste")
			(net "GND")
		)
		(pad "10_19" smd rect
			(at 0 2.899918 270)
			(size 0.6096 4.318)
			(layers "F.Cu" "F.Mask" "F.Paste")
			(net "SW_P0V8_PEX1_PH2")
		)
		(pad "25_29" smd rect
			(at 1.549908 -1.279906 90)
			(size 2.0574 2.3114)
			(layers "F.Cu" "F.Mask" "F.Paste")
			(net "SW_P12V_P0V8_PEX1_FLT")
		)
		(pad "30" smd rect
			(at 2.05994 -2.899918 180)
			(size 0.2286 0.6096)
			(layers "F.Cu" "F.Mask" "F.Paste")
			(net "SW_P12V_P0V8_PEX1_FLT")
		)
		(pad "31" smd rect
			(at 1.610106 -2.899918 180)
			(size 0.2286 0.6096)
			(layers "F.Cu" "F.Mask" "F.Paste")
			(net "NC_P0V8_PEX1_PH2_NC3")
		)
		(pad "32" smd rect
			(at 1.160018 -2.899918 180)
			(size 0.2286 0.6096)
			(layers "F.Cu" "F.Mask" "F.Paste")
			(net "SW_P0V8_PEX1_PHASE2")
		)
		(pad "33" smd rect
			(at 0.70993 -2.899918 180)
			(size 0.2286 0.6096)
			(layers "F.Cu" "F.Mask" "F.Paste")
			(net "SW_P0V8_PEX1_BOOT2")
		)
		(pad "34" smd rect
			(at 0.260096 -2.899918 180)
			(size 0.2286 0.6096)
			(layers "F.Cu" "F.Mask" "F.Paste")
			(net "P0V8_PEX1_PWM2")
		)
		(pad "35" smd rect
			(at -0.189992 -2.899918 180)
			(size 0.2286 0.6096)
			(layers "F.Cu" "F.Mask" "F.Paste")
			(net "P0V8_PEX0_EN4")
		)
		(pad "36" smd rect
			(at -0.64008 -2.899918 180)
			(size 0.2286 0.6096)
			(layers "F.Cu" "F.Mask" "F.Paste")
			(net "P0V8_PEX1_TSEN")
		)
		(pad "37" smd rect
			(at -1.089914 -2.899918 180)
			(size 0.2286 0.6096)
			(layers "F.Cu" "F.Mask" "F.Paste")
			(net "P0V8_PEX1_LSET2")
		)
		(pad "38" smd rect
			(at -1.540002 -2.899918 180)
			(size 0.2286 0.6096)
			(layers "F.Cu" "F.Mask" "F.Paste")
			(net "P0V8_PEX1_ISEN2")
		)
		(pad "39" smd rect
			(at -1.99009 -2.899918 180)
			(size 0.2286 0.6096)
			(layers "F.Cu" "F.Mask" "F.Paste")
			(net "P0V8_PEX0_VREF")
		)
		(pad "40" smd rect
			(at -0.87503 -1.27508 180)
			(size 1.7526 1.9558)
			(layers "F.Cu" "F.Mask" "F.Paste")
			(net "GND")
		)
		(pad "41" smd rect
			(at -1.525016 0.249936 90)
			(size 0.3048 0.4572)
			(layers "F.Cu" "F.Mask" "F.Paste")
			(net "NC_P0V8_PEX1_PH2_NC2")
		)
		(zone
			(layer "F.Cu")
			(hatch none 0.5)
			(connect_pads
				(clearance 0)
			)
			(min_thickness 0.25)
			(keepout
				(tracks not_allowed)
				(vias allowed)
				(pads allowed)
				(copperpour not_allowed)
				(footprints allowed)
			)
			(placement
				(enabled no)
				(sheetname "")
			)
			(fill
				(thermal_gap 0.5)
				(thermal_bridge_width 0.5)
				(island_removal_mode 0)
			)
			(polygon
				(pts
					(xy 133.291326 -287.899094) (xy 133.291326 -287.149794) (xy 128.291082 -287.149794) (xy 128.291082 -287.899094)
					(xy 128.581404 -287.899094) (xy 128.581404 -287.443418) (xy 133.001004 -287.443418) (xy 133.001004 -287.899094)
				)
			)
		)
	)
	(footprint ""
		(layer "F.Cu")
		(at 134.181596 -293.816786 -90)
		(property "Reference" "PC116"
			(at 0 0 270)
			(layer "F.SilkS")
			(hide yes)
			(effects
				(font
					(size 1.27 1.27)
				)
			)
		)
		(property "Value" ""
			(at 0 0 270)
			(layer "F.Fab")
			(effects
				(font
					(size 1.27 1.27)
				)
			)
		)
		(duplicate_pad_numbers_are_jumpers no)
		(fp_line
			(start -0.7874 0.4064)
			(end -0.7874 -0.4064)
			(stroke
				(width 0.1524)
				(type default)
			)
			(layer "F.SilkS")
		)
		(fp_line
			(start 0.7874 0.4064)
			(end -0.7874 0.4064)
			(stroke
				(width 0.1524)
				(type default)
			)
			(layer "F.SilkS")
		)
		(fp_line
			(start -0.7874 -0.4064)
			(end 0.7874 -0.4064)
			(stroke
				(width 0.1524)
				(type default)
			)
			(layer "F.SilkS")
		)
		(fp_line
			(start 0.7874 -0.4064)
			(end 0.7874 0.4064)
			(stroke
				(width 0.1524)
				(type default)
			)
			(layer "F.SilkS")
		)
		(fp_line
			(start -0.67945 0.3048)
			(end -0.67945 -0.305054)
			(stroke
				(width 0.1)
				(type default)
			)
			(layer "F.Fab")
		)
		(fp_line
			(start -0.12065 0.3048)
			(end -0.67945 0.3048)
			(stroke
				(width 0.1)
				(type default)
			)
			(layer "F.Fab")
		)
		(fp_line
			(start 0.120396 0.3048)
			(end 0.120396 0.2794)
			(stroke
				(width 0.1)
				(type default)
			)
			(layer "F.Fab")
		)
		(fp_line
			(start 0.67945 0.3048)
			(end 0.120396 0.3048)
			(stroke
				(width 0.1)
				(type default)
			)
			(layer "F.Fab")
		)
		(fp_line
			(start -0.12065 0.2794)
			(end -0.12065 0.3048)
			(stroke
				(width 0.1)
				(type default)
			)
			(layer "F.Fab")
		)
		(fp_line
			(start 0.120396 0.2794)
			(end -0.12065 0.2794)
			(stroke
				(width 0.1)
				(type default)
			)
			(layer "F.Fab")
		)
		(fp_line
			(start -0.12065 -0.2794)
			(end 0.12065 -0.2794)
			(stroke
				(width 0.1)
				(type default)
			)
			(layer "F.Fab")
		)
		(fp_line
			(start 0.12065 -0.2794)
			(end 0.12065 -0.3048)
			(stroke
				(width 0.1)
				(type default)
			)
			(layer "F.Fab")
		)
		(fp_line
			(start 0.12065 -0.3048)
			(end 0.67945 -0.3048)
			(stroke
				(width 0.1)
				(type default)
			)
			(layer "F.Fab")
		)
		(fp_line
			(start 0.67945 -0.3048)
			(end 0.67945 0.3048)
			(stroke
				(width 0.1)
				(type default)
			)
			(layer "F.Fab")
		)
		(fp_line
			(start -0.67945 -0.305054)
			(end -0.12065 -0.305054)
			(stroke
				(width 0.1)
				(type default)
			)
			(layer "F.Fab")
		)
		(fp_line
			(start -0.12065 -0.305054)
			(end -0.12065 -0.2794)
			(stroke
				(width 0.1)
				(type default)
			)
			(layer "F.Fab")
		)
		(pad "1" smd circle
			(at -0.40005 0 270)
			(size 0 0)
			(layers "F.Cu" "F.Mask" "F.Paste")
			(net "P0V8_PEX1")
		)
		(pad "2" smd circle
			(at 0.40005 0 270)
			(size 0 0)
			(layers "F.Cu" "F.Mask" "F.Paste")
			(net "GND")
		)
	)
	(footprint ""
		(layer "F.Cu")
		(at 379.633988 -8.900922)
		(property "Reference" "R5821"
			(at 0 0 0)
			(layer "F.SilkS")
			(hide yes)
			(effects
				(font
					(size 1.27 1.27)
				)
			)
		)
		(property "Value" ""
			(at 0 0 0)
			(layer "F.Fab")
			(effects
				(font
					(size 1.27 1.27)
				)
			)
		)
		(duplicate_pad_numbers_are_jumpers no)
		(fp_line
			(start -0.7874 -0.4064)
			(end 0.7874 -0.4064)
			(stroke
				(width 0.1524)
				(type default)
			)
			(layer "F.SilkS")
		)
		(fp_line
			(start -0.7874 0.4064)
			(end -0.7874 -0.4064)
			(stroke
				(width 0.1524)
				(type default)
			)
			(layer "F.SilkS")
		)
		(fp_line
			(start 0.7874 -0.4064)
			(end 0.7874 0.4064)
			(stroke
				(width 0.1524)
				(type default)
			)
			(layer "F.SilkS")
		)
		(fp_line
			(start 0.7874 0.4064)
			(end -0.7874 0.4064)
			(stroke
				(width 0.1524)
				(type default)
			)
			(layer "F.SilkS")
		)
		(fp_line
			(start -0.67945 -0.305054)
			(end -0.12065 -0.305054)
			(stroke
				(width 0.1)
				(type default)
			)
			(layer "F.Fab")
		)
		(fp_line
			(start -0.67945 0.3048)
			(end -0.67945 -0.305054)
			(stroke
				(width 0.1)
				(type default)
			)
			(layer "F.Fab")
		)
		(fp_line
			(start -0.12065 -0.305054)
			(end -0.12065 -0.2794)
			(stroke
				(width 0.1)
				(type default)
			)
			(layer "F.Fab")
		)
		(fp_line
			(start -0.12065 -0.2794)
			(end 0.12065 -0.2794)
			(stroke
				(width 0.1)
				(type default)
			)
			(layer "F.Fab")
		)
		(fp_line
			(start -0.12065 0.2794)
			(end -0.12065 0.3048)
			(stroke
				(width 0.1)
				(type default)
			)
			(layer "F.Fab")
		)
		(fp_line
			(start -0.12065 0.3048)
			(end -0.67945 0.3048)
			(stroke
				(width 0.1)
				(type default)
			)
			(layer "F.Fab")
		)
		(fp_line
			(start 0.120396 0.2794)
			(end -0.12065 0.2794)
			(stroke
				(width 0.1)
				(type default)
			)
			(layer "F.Fab")
		)
		(fp_line
			(start 0.120396 0.3048)
			(end 0.120396 0.2794)
			(stroke
				(width 0.1)
				(type default)
			)
			(layer "F.Fab")
		)
		(fp_line
			(start 0.12065 -0.3048)
			(end 0.67945 -0.3048)
			(stroke
				(width 0.1)
				(type default)
			)
			(layer "F.Fab")
		)
		(fp_line
			(start 0.12065 -0.2794)
			(end 0.12065 -0.3048)
			(stroke
				(width 0.1)
				(type default)
			)
			(layer "F.Fab")
		)
		(fp_line
			(start 0.67945 -0.3048)
			(end 0.67945 0.3048)
			(stroke
				(width 0.1)
				(type default)
			)
			(layer "F.Fab")
		)
		(fp_line
			(start 0.67945 0.3048)
			(end 0.120396 0.3048)
			(stroke
				(width 0.1)
				(type default)
			)
			(layer "F.Fab")
		)
		(pad "1" smd circle
			(at -0.40005 0)
			(size 0 0)
			(layers "F.Cu" "F.Mask" "F.Paste")
			(net "LM75_3_A0")
		)
		(pad "2" smd circle
			(at 0.40005 0)
			(size 0 0)
			(layers "F.Cu" "F.Mask" "F.Paste")
			(net "GND")
		)
	)
	(footprint ""
		(layer "F.Cu")
		(at 387.580632 -100.203254)
		(property "Reference" "C697"
			(at 0 0 0)
			(layer "F.SilkS")
			(hide yes)
			(effects
				(font
					(size 1.27 1.27)
				)
			)
		)
		(property "Value" ""
			(at 0 0 0)
			(layer "F.Fab")
			(effects
				(font
					(size 1.27 1.27)
				)
			)
		)
		(duplicate_pad_numbers_are_jumpers no)
		(fp_line
			(start -0.299974 -0.150114)
			(end 0.299974 -0.150114)
			(stroke
				(width 0.1)
				(type default)
			)
			(layer "F.Fab")
		)
		(fp_line
			(start -0.299974 0.150114)
			(end -0.299974 -0.150114)
			(stroke
				(width 0.1)
				(type default)
			)
			(layer "F.Fab")
		)
		(fp_line
			(start 0.299974 -0.150114)
			(end 0.299974 0.150114)
			(stroke
				(width 0.1)
				(type default)
			)
			(layer "F.Fab")
		)
		(fp_line
			(start 0.299974 0.150114)
			(end -0.299974 0.150114)
			(stroke
				(width 0.1)
				(type default)
			)
			(layer "F.Fab")
		)
		(pad "1" smd rect
			(at -0.2667 0)
			(size 0.3048 0.381)
			(layers "F.Cu" "F.Mask" "F.Paste")
			(net "P5E_PEX3_STN1_TX_DN<16>")
		)
		(pad "2" smd rect
			(at 0.2667 0)
			(size 0.3048 0.381)
			(layers "F.Cu" "F.Mask" "F.Paste")
			(net "P5E_PEX3_STN1_TX_C_DN<16>")
		)
	)
	(footprint ""
		(layer "F.Cu")
		(at 375.18594 -350.098614 90)
		(property "Reference" "C765"
			(at 0 0 90)
			(layer "F.SilkS")
			(hide yes)
			(effects
				(font
					(size 1.27 1.27)
				)
			)
		)
		(property "Value" ""
			(at 0 0 90)
			(layer "F.Fab")
			(effects
				(font
					(size 1.27 1.27)
				)
			)
		)
		(duplicate_pad_numbers_are_jumpers no)
		(fp_line
			(start 0.299974 -0.150114)
			(end 0.299974 0.150114)
			(stroke
				(width 0.1)
				(type default)
			)
			(layer "F.Fab")
		)
		(fp_line
			(start -0.299974 -0.150114)
			(end 0.299974 -0.150114)
			(stroke
				(width 0.1)
				(type default)
			)
			(layer "F.Fab")
		)
		(fp_line
			(start 0.299974 0.150114)
			(end -0.299974 0.150114)
			(stroke
				(width 0.1)
				(type default)
			)
			(layer "F.Fab")
		)
		(fp_line
			(start -0.299974 0.150114)
			(end -0.299974 -0.150114)
			(stroke
				(width 0.1)
				(type default)
			)
			(layer "F.Fab")
		)
		(pad "1" smd rect
			(at -0.2667 0 90)
			(size 0.3048 0.381)
			(layers "F.Cu" "F.Mask" "F.Paste")
			(net "P5E_PEX3_STN6_TX_DN<110>")
		)
		(pad "2" smd rect
			(at 0.2667 0 90)
			(size 0.3048 0.381)
			(layers "F.Cu" "F.Mask" "F.Paste")
			(net "P5E_PEX3_STN6_TX_C_DN<110>")
		)
	)
	(footprint ""
		(layer "F.Cu")
		(at 144.149318 -293.796212 -90)
		(property "Reference" "C3192"
			(at 0 0 270)
			(layer "F.SilkS")
			(hide yes)
			(effects
				(font
					(size 1.27 1.27)
				)
			)
		)
		(property "Value" ""
			(at 0 0 270)
			(layer "F.Fab")
			(effects
				(font
					(size 1.27 1.27)
				)
			)
		)
		(duplicate_pad_numbers_are_jumpers no)
		(fp_line
			(start -0.299974 0.150114)
			(end -0.299974 -0.150114)
			(stroke
				(width 0.1)
				(type default)
			)
			(layer "F.Fab")
		)
		(fp_line
			(start 0.299974 0.150114)
			(end -0.299974 0.150114)
			(stroke
				(width 0.1)
				(type default)
			)
			(layer "F.Fab")
		)
		(fp_line
			(start -0.299974 -0.150114)
			(end 0.299974 -0.150114)
			(stroke
				(width 0.1)
				(type default)
			)
			(layer "F.Fab")
		)
		(fp_line
			(start 0.299974 -0.150114)
			(end 0.299974 0.150114)
			(stroke
				(width 0.1)
				(type default)
			)
			(layer "F.Fab")
		)
		(pad "1" smd rect
			(at -0.2667 0 270)
			(size 0.3048 0.381)
			(layers "F.Cu" "F.Mask" "F.Paste")
			(net "P1V8_PLL0_PEX1")
		)
		(pad "2" smd rect
			(at 0.2667 0 270)
			(size 0.3048 0.381)
			(layers "F.Cu" "F.Mask" "F.Paste")
			(net "GND")
		)
	)
)
